# BASEBOARD_FAB2 (Tioga Pass) — schematic netlist excerpt (pin names and nets, part order shuffled) for the footprints in the layout excerpt that follows; sources: Cadence DE-HDL packaged netlist, KiCad conversion of Wiwynn_Tioga_Pass_MB.brd

C1D6  CAP  0.22UF 16V 10% X7R  pkg 0402  page 208 : A = P5V_STBY ; B = GND
R25W46  120R2F-GP  1%  pkg RCL_GP  page 151 : \1\ = BMC_M_A8 ; \2\ = P1V2_AUX_BMC
R1C30  RES  22.1 1.0% CHIP  pkg 0402  page 206 : A = VR_VRRDY_PVCCIN_CPU1 ; B = PWRGD_PVCCIN_CPU1

(kicad_pcb
	(version 20260206)
	(generator "pcbnew")
	(generator_version "10.0")
	(general
		(thickness 1.6)
		(legacy_teardrops no)
	)
	(paper "A4")
	(title_block
		(title "Wiwynn_Tioga_Pass_MB.brd")
		(comment 1 "Tioga Pass / footprints 117-119 of 4770")
	)
	(layers
		(0 "F.Cu" signal "TOP")
		(4 "In1.Cu" signal "L2GND")
		(6 "In2.Cu" signal "L3")
		(8 "In3.Cu" signal "L4GND")
		(10 "In4.Cu" signal "L5")
		(12 "In5.Cu" signal "L6GND")
		(14 "In6.Cu" signal "L7VCC")
		(16 "In7.Cu" signal "L8VCC")
		(18 "In8.Cu" signal "L9GND")
		(20 "In9.Cu" signal "L10")
		(22 "In10.Cu" signal "L11GND")
		(24 "In11.Cu" signal "L12")
		(26 "In12.Cu" signal "L13GND")
		(2 "B.Cu" signal "BOTTOM")
		(9 "F.Adhes" user "F.Adhesive")
		(11 "B.Adhes" user "B.Adhesive")
		(13 "F.Paste" user "Package Geometry/Pastemask Top")
		(15 "B.Paste" user "Package Geometry/Pastemask Bottom")
		(5 "F.SilkS" user "Ref Des/Silkscreen Top")
		(7 "B.SilkS" user "Ref Des/Silkscreen Bottom")
		(1 "F.Mask" user "Board Geometry/Soldermask Top")
		(3 "B.Mask" user "Board Geometry/Soldermask Bottom")
		(17 "Dwgs.User" user "User.Drawings")
		(19 "Cmts.User" user "User.Comments")
		(21 "Eco1.User" user "User.Eco1")
		(23 "Eco2.User" user "User.Eco2")
		(25 "Edge.Cuts" user "Board Geometry/Outline")
		(27 "Margin" user)
		(31 "F.CrtYd" user "Package Geometry/Place Bound Top")
		(29 "B.CrtYd" user "Package Geometry/Place Bound Bottom")
		(35 "F.Fab" user "Ref Des/Assembly Top")
		(33 "B.Fab" user "Ref Des/Assembly Bottom")
	)
	(footprint ""
		(layer "F.Cu")
		(at 451.85838 -37.1475 90)
		(property "Reference" "R25W46"
			(at 0 0 90)
			(layer "F.SilkS")
			(hide yes)
			(effects
				(font
					(size 1.27 1.27)
				)
			)
		)
		(property "Value" "*"
			(at 0.064008 -4.108196 90)
			(unlocked yes)
			(layer "F.Fab")
			(hide yes)
			(effects
				(font
					(size 1.27 1.016)
					(thickness 0.1524)
				)
			)
		)
		(property "Device Type" "120R2F-GP_RCL_GP-120R2F-GP,64.A"
			(at 0.064008 -5.632196 90)
			(unlocked yes)
			(layer "F.Fab")
			(hide yes)
			(effects
				(font
					(size 1.27 1.016)
					(thickness 0.1524)
				)
			)
		)
		(duplicate_pad_numbers_are_jumpers no)
		(fp_line
			(start 0.508 -0.9398)
			(end -0.508 -0.9398)
			(stroke
				(width 0.1524)
				(type default)
			)
			(layer "F.SilkS")
		)
		(fp_line
			(start -0.508 -0.9398)
			(end -0.508 0.9398)
			(stroke
				(width 0.1524)
				(type default)
			)
			(layer "F.SilkS")
		)
		(fp_rect
			(start -0.508 0.9398)
			(end 0.508 -0.9398)
			(stroke
				(width 0)
				(type default)
			)
			(fill no)
			(layer "F.CrtYd")
		)
		(fp_rect
			(start -0.508 0.9398)
			(end 0.508 -0.9398)
			(stroke
				(width 0)
				(type default)
			)
			(fill no)
			(layer "F.Fab")
		)
		(pad "1" smd custom
			(at 0 -0.4445 90)
			(size 0.1397 0.1397)
			(layers "F.Cu" "F.Mask" "F.Paste")
			(net "BMC_M_A8")
			(options
				(clearance outline)
				(anchor circle)
			)
			(primitives
				(gr_poly
					(pts
						(arc
							(start -0.1778 -0.2794)
							(mid -0.249642 -0.249642)
							(end -0.2794 -0.1778)
						)
						(arc
							(start -0.2794 0.1778)
							(mid -0.249642 0.249642)
							(end -0.1778 0.2794)
						)
						(arc
							(start 0.1778 0.2794)
							(mid 0.249642 0.249642)
							(end 0.2794 0.1778)
						)
						(arc
							(start 0.2794 -0.1778)
							(mid 0.249642 -0.249642)
							(end 0.1778 -0.2794)
						)
					)
					(width 0)
					(fill yes)
				)
			)
		)
		(pad "2" smd custom
			(at 0 0.4445 90)
			(size 0.1397 0.1397)
			(layers "F.Cu" "F.Mask" "F.Paste")
			(net "P1V2_AUX_BMC")
			(options
				(clearance outline)
				(anchor circle)
			)
			(primitives
				(gr_poly
					(pts
						(arc
							(start -0.1778 -0.2794)
							(mid -0.249642 -0.249642)
							(end -0.2794 -0.1778)
						)
						(arc
							(start -0.2794 0.1778)
							(mid -0.249642 0.249642)
							(end -0.1778 0.2794)
						)
						(arc
							(start 0.1778 0.2794)
							(mid 0.249642 0.249642)
							(end 0.2794 0.1778)
						)
						(arc
							(start 0.2794 -0.1778)
							(mid 0.249642 -0.249642)
							(end 0.1778 -0.2794)
						)
					)
					(width 0)
					(fill yes)
				)
			)
		)
	)
	(footprint ""
		(layer "F.Cu")
		(at 33.178496 -77.605382 90)
		(property "Reference" "C1D6"
			(at 0 0 90)
			(layer "F.SilkS")
			(hide yes)
			(effects
				(font
					(size 1.27 1.27)
				)
			)
		)
		(property "Value" ""
			(at 0 0 90)
			(layer "F.Fab")
			(effects
				(font
					(size 1.27 1.27)
				)
			)
		)
		(duplicate_pad_numbers_are_jumpers no)
		(fp_rect
			(start 0.3048 0.9906)
			(end -0.3048 -0.1016)
			(stroke
				(width 0)
				(type default)
			)
			(fill no)
			(layer "F.CrtYd")
		)
		(fp_line
			(start 0.3048 -0.1016)
			(end -0.3048 -0.1016)
			(stroke
				(width 0.1)
				(type default)
			)
			(layer "F.Fab")
		)
		(fp_line
			(start -0.3048 -0.1016)
			(end -0.3048 0.9906)
			(stroke
				(width 0.1)
				(type default)
			)
			(layer "F.Fab")
		)
		(fp_line
			(start 0.3048 0.9906)
			(end 0.3048 -0.1016)
			(stroke
				(width 0.1)
				(type default)
			)
			(layer "F.Fab")
		)
		(fp_line
			(start -0.3048 0.9906)
			(end 0.3048 0.9906)
			(stroke
				(width 0.1)
				(type default)
			)
			(layer "F.Fab")
		)
		(pad "1" smd rect
			(at 0 0 90)
			(size 0.508 0.508)
			(layers "F.Cu" "F.Mask" "F.Paste")
			(net "P5V_STBY")
		)
		(pad "2" smd rect
			(at 0 0.889 90)
			(size 0.508 0.508)
			(layers "F.Cu" "F.Mask" "F.Paste")
			(net "GND")
		)
		(zone
			(layer "F.Cu")
			(hatch none 0.5)
			(connect_pads
				(clearance 0)
			)
			(min_thickness 0.25)
			(keepout
				(tracks not_allowed)
				(vias allowed)
				(pads allowed)
				(copperpour not_allowed)
				(footprints allowed)
			)
			(placement
				(enabled no)
				(sheetname "")
			)
			(fill
				(thermal_gap 0.5)
				(thermal_bridge_width 0.5)
				(island_removal_mode 0)
			)
			(polygon
				(pts
					(xy 33.813496 -77.859382) (xy 33.432496 -77.859382) (xy 33.432496 -77.351382) (xy 33.813496 -77.351382)
				)
			)
		)
		(zone
			(layer "F.Cu")
			(hatch none 0.5)
			(connect_pads
				(clearance 0)
			)
			(min_thickness 0.25)
			(keepout
				(tracks allowed)
				(vias not_allowed)
				(pads allowed)
				(copperpour not_allowed)
				(footprints allowed)
			)
			(placement
				(enabled no)
				(sheetname "")
			)
			(fill
				(thermal_gap 0.5)
				(thermal_bridge_width 0.5)
				(island_removal_mode 0)
			)
			(polygon
				(pts
					(xy 33.813496 -77.859382) (xy 33.432496 -77.859382) (xy 33.432496 -77.351382) (xy 33.813496 -77.351382)
				)
			)
		)
	)
	(footprint ""
		(layer "F.Cu")
		(at 14.732 -88.4936 -90)
		(property "Reference" "R1C30"
			(at 0 0 270)
			(layer "F.SilkS")
			(hide yes)
			(effects
				(font
					(size 1.27 1.27)
				)
			)
		)
		(property "Value" ""
			(at 0 0 270)
			(layer "F.Fab")
			(effects
				(font
					(size 1.27 1.27)
				)
			)
		)
		(duplicate_pad_numbers_are_jumpers no)
		(fp_rect
			(start 0.2794 0.9906)
			(end -0.2794 -0.1016)
			(stroke
				(width 0)
				(type default)
			)
			(fill no)
			(layer "F.CrtYd")
		)
		(fp_line
			(start -0.2794 0.9906)
			(end 0.2794 0.9906)
			(stroke
				(width 0.1)
				(type default)
			)
			(layer "F.Fab")
		)
		(fp_line
			(start 0.2794 0.9906)
			(end 0.2794 -0.1016)
			(stroke
				(width 0.1)
				(type default)
			)
			(layer "F.Fab")
		)
		(fp_line
			(start -0.2794 -0.1016)
			(end -0.2794 0.9906)
			(stroke
				(width 0.1)
				(type default)
			)
			(layer "F.Fab")
		)
		(fp_line
			(start 0.2794 -0.1016)
			(end -0.2794 -0.1016)
			(stroke
				(width 0.1)
				(type default)
			)
			(layer "F.Fab")
		)
		(pad "1" smd rect
			(at 0 0 270)
			(size 0.508 0.508)
			(layers "F.Cu" "F.Mask" "F.Paste")
			(net "VR_VRRDY_PVCCIN_CPU1")
		)
		(pad "2" smd rect
			(at 0 0.889 270)
			(size 0.508 0.508)
			(layers "F.Cu" "F.Mask" "F.Paste")
			(net "PWRGD_PVCCIN_CPU1")
		)
		(zone
			(layer "F.Cu")
			(hatch none 0.5)
			(connect_pads
				(clearance 0)
			)
			(min_thickness 0.25)
			(keepout
				(tracks not_allowed)
				(vias allowed)
				(pads allowed)
				(copperpour not_allowed)
				(footprints allowed)
			)
			(placement
				(enabled no)
				(sheetname "")
			)
			(fill
				(thermal_gap 0.5)
				(thermal_bridge_width 0.5)
				(island_removal_mode 0)
			)
			(polygon
				(pts
					(xy 14.097 -88.2396) (xy 14.478 -88.2396) (xy 14.478 -88.7476) (xy 14.097 -88.7476)
				)
			)
		)
		(zone
			(layer "F.Cu")
			(hatch none 0.5)
			(connect_pads
				(clearance 0)
			)
			(min_thickness 0.25)
			(keepout
				(tracks allowed)
				(vias not_allowed)
				(pads allowed)
				(copperpour not_allowed)
				(footprints allowed)
			)
			(placement
				(enabled no)
				(sheetname "")
			)
			(fill
				(thermal_gap 0.5)
				(thermal_bridge_width 0.5)
				(island_removal_mode 0)
			)
			(polygon
				(pts
					(xy 14.097 -88.2396) (xy 14.478 -88.2396) (xy 14.478 -88.7476) (xy 14.097 -88.7476)
				)
			)
		)
	)
)
